(kicad_pcb
	(version 20241229)
	(generator "pcbnew")
	(generator_version "9.0")
	(general
		(thickness 1.6)
		(legacy_teardrops no)
	)
	(paper "A4")
	(title_block
		(title "LPDDR4 testbed")
		(date "2024-03-26")
		(rev "1.2.2")
		(comment 9 "footprints 47-53 of 66")
	)
	(layers
		(0 "F.Cu" signal)
		(4 "In1.Cu" power)
		(6 "In2.Cu" power)
		(8 "In3.Cu" signal)
		(10 "In4.Cu" signal)
		(2 "B.Cu" signal)
		(9 "F.Adhes" user "F.Adhesive")
		(11 "B.Adhes" user "B.Adhesive")
		(13 "F.Paste" user)
		(15 "B.Paste" user)
		(5 "F.SilkS" user "F.Silkscreen")
		(7 "B.SilkS" user "B.Silkscreen")
		(1 "F.Mask" user)
		(3 "B.Mask" user)
		(17 "Dwgs.User" user "User.Drawings")
		(19 "Cmts.User" user "User.Comments")
		(21 "Eco1.User" user "User.Eco1")
		(23 "Eco2.User" user "User.Eco2")
		(25 "Edge.Cuts" user)
		(27 "Margin" user)
		(31 "F.CrtYd" user "F.Courtyard")
		(29 "B.CrtYd" user "B.Courtyard")
		(35 "F.Fab" user)
		(33 "B.Fab" user)
	)
	(footprint "antmicro-footprints:R_0402_1005Metric"
		(layer "F.Cu")
		(at 126.555 89.72 -90)
		(descr "Resistor SMD 0402")
		(tags "resistor SMD 0402")
		(property "Reference" "R14"
			(at 1.03 0.58 270)
			(layer "F.SilkS")
			(effects
				(font
					(size 0.7 0.7)
					(thickness 0.15)
				)
				(justify left bottom)
			)
		)
		(property "Value" "R_10k_0402"
			(at 0 1.4 270)
			(layer "F.Fab")
			(effects
				(font
					(size 0.7 0.7)
					(thickness 0.15)
				)
				(justify left bottom)
			)
		)
		(property "Description" "10k resistor in 0402 package with 1% tolerance"
			(at 0 0 270)
			(layer "F.Fab")
			(hide yes)
			(effects
				(font
					(size 1.27 1.27)
					(thickness 0.15)
				)
			)
		)
		(property "Author" "Antmicro"
			(at 36.835 216.275 0)
			(layer "F.Fab")
			(hide yes)
			(effects
				(font
					(size 1 1)
					(thickness 0.15)
				)
			)
		)
		(property "License" "Apache-2.0"
			(at 36.835 216.275 0)
			(layer "F.Fab")
			(hide yes)
			(effects
				(font
					(size 1 1)
					(thickness 0.15)
				)
			)
		)
		(property "MPN" "CRCW040210K0FKEDHP"
			(at 36.835 216.275 0)
			(layer "F.Fab")
			(hide yes)
			(effects
				(font
					(size 1 1)
					(thickness 0.15)
				)
			)
		)
		(property "Manufacturer" "VISHAY"
			(at 36.835 216.275 0)
			(layer "F.Fab")
			(hide yes)
			(effects
				(font
					(size 1 1)
					(thickness 0.15)
				)
			)
		)
		(property "Tolerance" "1%"
			(at 36.835 216.275 0)
			(layer "F.Fab")
			(hide yes)
			(effects
				(font
					(size 1 1)
					(thickness 0.15)
				)
			)
		)
		(property "Val" "10k"
			(at 36.835 216.275 0)
			(layer "F.Fab")
			(hide yes)
			(effects
				(font
					(size 1 1)
					(thickness 0.15)
				)
			)
		)
		(sheetname "EEPROM")
		(sheetfile "EEPROM.kicad_sch")
		(attr smd)
		(fp_rect
			(start -0.93 -0.47)
			(end 0.93 0.47)
			(stroke
				(width 0.05)
				(type solid)
			)
			(fill no)
			(layer "F.CrtYd")
		)
		(fp_rect
			(start -0.5 -0.25)
			(end 0.5 0.25)
			(stroke
				(width 0.15)
				(type solid)
			)
			(fill no)
			(layer "F.Fab")
		)
		(pad "1" smd roundrect
			(at -0.485 0 270)
			(size 0.59 0.64)
			(layers "F.Cu" "F.Mask" "F.Paste")
			(roundrect_rratio 0.25)
			(net 187 "VDD1")
			(pintype "passive")
		)
		(pad "2" smd roundrect
			(at 0.485 0 270)
			(size 0.59 0.64)
			(layers "F.Cu" "F.Mask" "F.Paste")
			(roundrect_rratio 0.25)
			(net 247 "SCL")
			(pintype "passive")
		)
	)
	(footprint "antmicro-footprints:R_0402_1005Metric"
		(layer "B.Cu")
		(at 151.775 83.1 90)
		(descr "Resistor SMD 0402")
		(tags "resistor SMD 0402")
		(property "Reference" "R3"
			(at -0.75 0.3 270)
			(layer "B.SilkS")
			(effects
				(font
					(size 0.7 0.7)
					(thickness 0.15)
				)
				(justify left bottom mirror)
			)
		)
		(property "Value" "R_10k_0402"
			(at 0 -1.4 270)
			(layer "B.Fab")
			(effects
				(font
					(size 0.7 0.7)
					(thickness 0.15)
				)
				(justify left bottom mirror)
			)
		)
		(property "Description" "10k resistor in 0402 package with 1% tolerance"
			(at 0 0 90)
			(layer "F.Fab")
			(hide yes)
			(effects
				(font
					(size 1.27 1.27)
					(thickness 0.15)
				)
			)
		)
		(property "Author" "Antmicro"
			(at 234.875 -68.675 0)
			(layer "B.Fab")
			(hide yes)
			(effects
				(font
					(size 1 1)
					(thickness 0.15)
				)
				(justify mirror)
			)
		)
		(property "License" "Apache-2.0"
			(at 234.875 -68.675 0)
			(layer "B.Fab")
			(hide yes)
			(effects
				(font
					(size 1 1)
					(thickness 0.15)
				)
				(justify mirror)
			)
		)
		(property "MPN" "CRCW040210K0FKEDHP"
			(at 234.875 -68.675 0)
			(layer "B.Fab")
			(hide yes)
			(effects
				(font
					(size 1 1)
					(thickness 0.15)
				)
				(justify mirror)
			)
		)
		(property "Manufacturer" "VISHAY"
			(at 234.875 -68.675 0)
			(layer "B.Fab")
			(hide yes)
			(effects
				(font
					(size 1 1)
					(thickness 0.15)
				)
				(justify mirror)
			)
		)
		(property "Tolerance" "1%"
			(at 234.875 -68.675 0)
			(layer "B.Fab")
			(hide yes)
			(effects
				(font
					(size 1 1)
					(thickness 0.15)
				)
				(justify mirror)
			)
		)
		(property "Val" "10k"
			(at 234.875 -68.675 0)
			(layer "B.Fab")
			(hide yes)
			(effects
				(font
					(size 1 1)
					(thickness 0.15)
				)
				(justify mirror)
			)
		)
		(sheetname "LPDDR4")
		(sheetfile "lpddr4.kicad_sch")
		(attr smd)
		(fp_rect
			(start -0.93 0.47)
			(end 0.93 -0.47)
			(stroke
				(width 0.05)
				(type solid)
			)
			(fill no)
			(layer "B.CrtYd")
		)
		(fp_rect
			(start -0.5 0.25)
			(end 0.5 -0.25)
			(stroke
				(width 0.15)
				(type solid)
			)
			(fill no)
			(layer "B.Fab")
		)
		(pad "1" smd roundrect
			(at -0.485 0 90)
			(size 0.59 0.64)
			(layers "B.Cu" "B.Mask" "B.Paste")
			(roundrect_rratio 0.25)
			(net 222 "CS0_B")
			(pintype "passive")
		)
		(pad "2" smd roundrect
			(at 0.485 0 90)
			(size 0.59 0.64)
			(layers "B.Cu" "B.Mask" "B.Paste")
			(roundrect_rratio 0.25)
			(net 36 "GND")
			(pintype "passive")
		)
	)
	(footprint "antmicro-footprints:C_0201"
		(layer "B.Cu")
		(at 149.375 79.95 -90)
		(descr "Capacitor SMD 0201")
		(tags "capacitor SMD 0201")
		(property "Reference" "C2"
			(at -0.8 0.4 90)
			(layer "B.SilkS")
			(effects
				(font
					(size 0.7 0.7)
					(thickness 0.15)
				)
				(justify left bottom mirror)
			)
		)
		(property "Value" "C_100n_0201"
			(at 0 -1.4 90)
			(layer "B.Fab")
			(effects
				(font
					(size 0.7 0.7)
					(thickness 0.15)
				)
				(justify left bottom mirror)
			)
		)
		(property "Description" " "
			(at 0 0 270)
			(layer "F.Fab")
			(hide yes)
			(effects
				(font
					(size 1.27 1.27)
					(thickness 0.15)
				)
			)
		)
		(property "Author" "Antmicro"
			(at 69.425 229.325 0)
			(layer "B.Fab")
			(hide yes)
			(effects
				(font
					(size 1 1)
					(thickness 0.15)
				)
				(justify mirror)
			)
		)
		(property "Dielectric" ""
			(at 69.425 229.325 0)
			(layer "B.Fab")
			(hide yes)
			(effects
				(font
					(size 1 1)
					(thickness 0.15)
				)
				(justify mirror)
			)
		)
		(property "License" "Apache-2.0"
			(at 69.425 229.325 0)
			(layer "B.Fab")
			(hide yes)
			(effects
				(font
					(size 1 1)
					(thickness 0.15)
				)
				(justify mirror)
			)
		)
		(property "MPN" "CC0201KRX6S5BB104"
			(at 69.425 229.325 0)
			(layer "B.Fab")
			(hide yes)
			(effects
				(font
					(size 1 1)
					(thickness 0.15)
				)
				(justify mirror)
			)
		)
		(property "Manufacturer" "YAGEO"
			(at 69.425 229.325 0)
			(layer "B.Fab")
			(hide yes)
			(effects
				(font
					(size 1 1)
					(thickness 0.15)
				)
				(justify mirror)
			)
		)
		(property "Val" "100n"
			(at 69.425 229.325 0)
			(layer "B.Fab")
			(hide yes)
			(effects
				(font
					(size 1 1)
					(thickness 0.15)
				)
				(justify mirror)
			)
		)
		(property "Voltage" ""
			(at 69.425 229.325 0)
			(layer "B.Fab")
			(hide yes)
			(effects
				(font
					(size 1 1)
					(thickness 0.15)
				)
				(justify mirror)
			)
		)
		(sheetname "LPDDR4")
		(sheetfile "lpddr4.kicad_sch")
		(attr smd)
		(fp_rect
			(start -0.72 0.38)
			(end 0.72 -0.38)
			(stroke
				(width 0.05)
				(type solid)
			)
			(fill no)
			(layer "B.CrtYd")
		)
		(fp_rect
			(start 0.3 -0.15)
			(end -0.301 0.149)
			(stroke
				(width 0.15)
				(type solid)
			)
			(fill no)
			(layer "B.Fab")
		)
		(pad "" smd roundrect
			(at -0.349 0.002 270)
			(size 0.318 0.36)
			(layers "B.Paste")
			(roundrect_rratio 0.25)
		)
		(pad "" smd roundrect
			(at 0.341 0.002 270)
			(size 0.318 0.36)
			(layers "B.Paste")
			(roundrect_rratio 0.25)
		)
		(pad "1" smd roundrect
			(at -0.321 0.002 270)
			(size 0.46 0.4)
			(layers "B.Cu" "B.Mask")
			(roundrect_rratio 0.25)
			(net 36 "GND")
			(pintype "passive")
		)
		(pad "2" smd roundrect
			(at 0.32 0.002 270)
			(size 0.46 0.4)
			(layers "B.Cu" "B.Mask")
			(roundrect_rratio 0.25)
			(net 189 "VDDQ")
			(pintype "passive")
		)
	)
	(footprint "antmicro-footprints:C_0201"
		(layer "B.Cu")
		(at 146.975 81.3 90)
		(descr "Capacitor SMD 0201")
		(tags "capacitor SMD 0201")
		(property "Reference" "C4"
			(at -0.65 -0.4 90)
			(layer "B.SilkS")
			(effects
				(font
					(size 0.7 0.7)
					(thickness 0.15)
				)
				(justify right bottom mirror)
			)
		)
		(property "Value" "C_100n_0201"
			(at 0 -1.4 90)
			(layer "B.Fab")
			(effects
				(font
					(size 0.7 0.7)
					(thickness 0.15)
				)
				(justify right bottom mirror)
			)
		)
		(property "Description" " "
			(at 0 0 90)
			(layer "F.Fab")
			(hide yes)
			(effects
				(font
					(size 1.27 1.27)
					(thickness 0.15)
				)
			)
		)
		(property "Author" "Antmicro"
			(at 228.275 -65.675 0)
			(layer "B.Fab")
			(hide yes)
			(effects
				(font
					(size 1 1)
					(thickness 0.15)
				)
				(justify mirror)
			)
		)
		(property "Dielectric" ""
			(at 228.275 -65.675 0)
			(layer "B.Fab")
			(hide yes)
			(effects
				(font
					(size 1 1)
					(thickness 0.15)
				)
				(justify mirror)
			)
		)
		(property "License" "Apache-2.0"
			(at 228.275 -65.675 0)
			(layer "B.Fab")
			(hide yes)
			(effects
				(font
					(size 1 1)
					(thickness 0.15)
				)
				(justify mirror)
			)
		)
		(property "MPN" "CC0201KRX6S5BB104"
			(at 228.275 -65.675 0)
			(layer "B.Fab")
			(hide yes)
			(effects
				(font
					(size 1 1)
					(thickness 0.15)
				)
				(justify mirror)
			)
		)
		(property "Manufacturer" "YAGEO"
			(at 228.275 -65.675 0)
			(layer "B.Fab")
			(hide yes)
			(effects
				(font
					(size 1 1)
					(thickness 0.15)
				)
				(justify mirror)
			)
		)
		(property "Val" "100n"
			(at 228.275 -65.675 0)
			(layer "B.Fab")
			(hide yes)
			(effects
				(font
					(size 1 1)
					(thickness 0.15)
				)
				(justify mirror)
			)
		)
		(property "Voltage" ""
			(at 228.275 -65.675 0)
			(layer "B.Fab")
			(hide yes)
			(effects
				(font
					(size 1 1)
					(thickness 0.15)
				)
				(justify mirror)
			)
		)
		(sheetname "LPDDR4")
		(sheetfile "lpddr4.kicad_sch")
		(attr smd)
		(fp_rect
			(start -0.72 0.38)
			(end 0.72 -0.38)
			(stroke
				(width 0.05)
				(type solid)
			)
			(fill no)
			(layer "B.CrtYd")
		)
		(fp_rect
			(start 0.3 -0.15)
			(end -0.301 0.149)
			(stroke
				(width 0.15)
				(type solid)
			)
			(fill no)
			(layer "B.Fab")
		)
		(pad "" smd roundrect
			(at -0.349 0.002 90)
			(size 0.318 0.36)
			(layers "B.Paste")
			(roundrect_rratio 0.25)
		)
		(pad "" smd roundrect
			(at 0.341 0.002 90)
			(size 0.318 0.36)
			(layers "B.Paste")
			(roundrect_rratio 0.25)
		)
		(pad "1" smd roundrect
			(at -0.321 0.002 90)
			(size 0.46 0.4)
			(layers "B.Cu" "B.Mask")
			(roundrect_rratio 0.25)
			(net 36 "GND")
			(pintype "passive")
		)
		(pad "2" smd roundrect
			(at 0.32 0.002 90)
			(size 0.46 0.4)
			(layers "B.Cu" "B.Mask")
			(roundrect_rratio 0.25)
			(net 189 "VDDQ")
			(pintype "passive")
		)
	)
	(footprint "antmicro-footprints:C_0201"
		(locked yes)
		(layer "B.Cu")
		(at 146.803 92.01 -90)
		(descr "Capacitor SMD 0201")
		(tags "capacitor SMD 0201")
		(property "Reference" "C7"
			(at 0.54 -0.372 90)
			(layer "B.SilkS")
			(effects
				(font
					(size 0.7 0.7)
					(thickness 0.15)
				)
				(justify left bottom mirror)
			)
		)
		(property "Value" "C_100n_0201"
			(at 0 -1.4 90)
			(layer "B.Fab")
			(effects
				(font
					(size 0.7 0.7)
					(thickness 0.15)
				)
				(justify left bottom mirror)
			)
		)
		(property "Description" " "
			(at 0 0 270)
			(layer "F.Fab")
			(hide yes)
			(effects
				(font
					(size 1.27 1.27)
					(thickness 0.15)
				)
			)
		)
		(property "Author" "Antmicro"
			(at 54.793 238.813 0)
			(layer "B.Fab")
			(hide yes)
			(effects
				(font
					(size 1 1)
					(thickness 0.15)
				)
				(justify mirror)
			)
		)
		(property "Dielectric" ""
			(at 54.793 238.813 0)
			(layer "B.Fab")
			(hide yes)
			(effects
				(font
					(size 1 1)
					(thickness 0.15)
				)
				(justify mirror)
			)
		)
		(property "License" "Apache-2.0"
			(at 54.793 238.813 0)
			(layer "B.Fab")
			(hide yes)
			(effects
				(font
					(size 1 1)
					(thickness 0.15)
				)
				(justify mirror)
			)
		)
		(property "MPN" "CC0201KRX6S5BB104"
			(at 54.793 238.813 0)
			(layer "B.Fab")
			(hide yes)
			(effects
				(font
					(size 1 1)
					(thickness 0.15)
				)
				(justify mirror)
			)
		)
		(property "Manufacturer" "YAGEO"
			(at 54.793 238.813 0)
			(layer "B.Fab")
			(hide yes)
			(effects
				(font
					(size 1 1)
					(thickness 0.15)
				)
				(justify mirror)
			)
		)
		(property "Val" "100n"
			(at 54.793 238.813 0)
			(layer "B.Fab")
			(hide yes)
			(effects
				(font
					(size 1 1)
					(thickness 0.15)
				)
				(justify mirror)
			)
		)
		(property "Voltage" ""
			(at 54.793 238.813 0)
			(layer "B.Fab")
			(hide yes)
			(effects
				(font
					(size 1 1)
					(thickness 0.15)
				)
				(justify mirror)
			)
		)
		(sheetname "LPDDR4")
		(sheetfile "lpddr4.kicad_sch")
		(attr smd)
		(fp_rect
			(start -0.72 0.38)
			(end 0.72 -0.38)
			(stroke
				(width 0.05)
				(type solid)
			)
			(fill no)
			(layer "B.CrtYd")
		)
		(fp_rect
			(start 0.3 -0.15)
			(end -0.301 0.149)
			(stroke
				(width 0.15)
				(type solid)
			)
			(fill no)
			(layer "B.Fab")
		)
		(pad "" smd roundrect
			(at -0.349 0.002 270)
			(size 0.318 0.36)
			(layers "B.Paste")
			(roundrect_rratio 0.25)
		)
		(pad "" smd roundrect
			(at 0.341 0.002 270)
			(size 0.318 0.36)
			(layers "B.Paste")
			(roundrect_rratio 0.25)
		)
		(pad "1" smd roundrect
			(at -0.321 0.002 270)
			(size 0.46 0.4)
			(layers "B.Cu" "B.Mask")
			(roundrect_rratio 0.25)
			(net 36 "GND")
			(pintype "passive")
		)
		(pad "2" smd roundrect
			(at 0.32 0.002 270)
			(size 0.46 0.4)
			(layers "B.Cu" "B.Mask")
			(roundrect_rratio 0.25)
			(net 189 "VDDQ")
			(pintype "passive")
		)
	)
	(footprint "antmicro-footprints:C_0201"
		(layer "B.Cu")
		(at 151.375 86.15)
		(descr "Capacitor SMD 0201")
		(tags "capacitor SMD 0201")
		(property "Reference" "C12"
			(at -1.3 1.2 0)
			(layer "B.SilkS")
			(effects
				(font
					(size 0.7 0.7)
					(thickness 0.15)
				)
				(justify right bottom mirror)
			)
		)
		(property "Value" "C_100n_0201"
			(at 0 -1.4 0)
			(layer "B.Fab")
			(effects
				(font
					(size 0.7 0.7)
					(thickness 0.15)
				)
				(justify right bottom mirror)
			)
		)
		(property "Description" " "
			(at 0 0 0)
			(layer "F.Fab")
			(hide yes)
			(effects
				(font
					(size 1.27 1.27)
					(thickness 0.15)
				)
			)
		)
		(property "Author" "Antmicro"
			(at 0 0 0)
			(layer "B.Fab")
			(hide yes)
			(effects
				(font
					(size 1 1)
					(thickness 0.15)
				)
				(justify mirror)
			)
		)
		(property "Dielectric" ""
			(at 0 0 0)
			(layer "B.Fab")
			(hide yes)
			(effects
				(font
					(size 1 1)
					(thickness 0.15)
				)
				(justify mirror)
			)
		)
		(property "License" "Apache-2.0"
			(at 0 0 0)
			(layer "B.Fab")
			(hide yes)
			(effects
				(font
					(size 1 1)
					(thickness 0.15)
				)
				(justify mirror)
			)
		)
		(property "MPN" "CC0201KRX6S5BB104"
			(at 0 0 0)
			(layer "B.Fab")
			(hide yes)
			(effects
				(font
					(size 1 1)
					(thickness 0.15)
				)
				(justify mirror)
			)
		)
		(property "Manufacturer" "YAGEO"
			(at 0 0 0)
			(layer "B.Fab")
			(hide yes)
			(effects
				(font
					(size 1 1)
					(thickness 0.15)
				)
				(justify mirror)
			)
		)
		(property "Val" "100n"
			(at 0 0 0)
			(layer "B.Fab")
			(hide yes)
			(effects
				(font
					(size 1 1)
					(thickness 0.15)
				)
				(justify mirror)
			)
		)
		(property "Voltage" ""
			(at 0 0 0)
			(layer "B.Fab")
			(hide yes)
			(effects
				(font
					(size 1 1)
					(thickness 0.15)
				)
				(justify mirror)
			)
		)
		(sheetname "LPDDR4")
		(sheetfile "lpddr4.kicad_sch")
		(attr smd)
		(fp_rect
			(start -0.72 0.38)
			(end 0.72 -0.38)
			(stroke
				(width 0.05)
				(type solid)
			)
			(fill no)
			(layer "B.CrtYd")
		)
		(fp_rect
			(start 0.3 -0.15)
			(end -0.301 0.149)
			(stroke
				(width 0.15)
				(type solid)
			)
			(fill no)
			(layer "B.Fab")
		)
		(pad "" smd roundrect
			(at -0.349 0.002)
			(size 0.318 0.36)
			(layers "B.Paste")
			(roundrect_rratio 0.25)
		)
		(pad "" smd roundrect
			(at 0.341 0.002)
			(size 0.318 0.36)
			(layers "B.Paste")
			(roundrect_rratio 0.25)
		)
		(pad "1" smd roundrect
			(at -0.321 0.002)
			(size 0.46 0.4)
			(layers "B.Cu" "B.Mask")
			(roundrect_rratio 0.25)
			(net 36 "GND")
			(pintype "passive")
		)
		(pad "2" smd roundrect
			(at 0.32 0.002)
			(size 0.46 0.4)
			(layers "B.Cu" "B.Mask")
			(roundrect_rratio 0.25)
			(net 188 "VDD2")
			(pintype "passive")
		)
	)
	(footprint "antmicro-footprints:C_0201"
		(layer "B.Cu")
		(at 152.575 81.4 90)
		(descr "Capacitor SMD 0201")
		(tags "capacitor SMD 0201")
		(property "Reference" "C13"
			(at 0.65 0.3 90)
			(layer "B.SilkS")
			(effects
				(font
					(size 0.7 0.7)
					(thickness 0.15)
				)
				(justify right bottom mirror)
			)
		)
		(property "Value" "C_100n_0201"
			(at 0 -1.4 90)
			(layer "B.Fab")
			(effects
				(font
					(size 0.7 0.7)
					(thickness 0.15)
				)
				(justify right bottom mirror)
			)
		)
		(property "Description" " "
			(at 0 0 90)
			(layer "F.Fab")
			(hide yes)
			(effects
				(font
					(size 1.27 1.27)
					(thickness 0.15)
				)
			)
		)
		(property "Author" "Antmicro"
			(at 233.975 -71.175 0)
			(layer "B.Fab")
			(hide yes)
			(effects
				(font
					(size 1 1)
					(thickness 0.15)
				)
				(justify mirror)
			)
		)
		(property "Dielectric" ""
			(at 233.975 -71.175 0)
			(layer "B.Fab")
			(hide yes)
			(effects
				(font
					(size 1 1)
					(thickness 0.15)
				)
				(justify mirror)
			)
		)
		(property "License" "Apache-2.0"
			(at 233.975 -71.175 0)
			(layer "B.Fab")
			(hide yes)
			(effects
				(font
					(size 1 1)
					(thickness 0.15)
				)
				(justify mirror)
			)
		)
		(property "MPN" "CC0201KRX6S5BB104"
			(at 233.975 -71.175 0)
			(layer "B.Fab")
			(hide yes)
			(effects
				(font
					(size 1 1)
					(thickness 0.15)
				)
				(justify mirror)
			)
		)
		(property "Manufacturer" "YAGEO"
			(at 233.975 -71.175 0)
			(layer "B.Fab")
			(hide yes)
			(effects
				(font
					(size 1 1)
					(thickness 0.15)
				)
				(justify mirror)
			)
		)
		(property "Val" "100n"
			(at 233.975 -71.175 0)
			(layer "B.Fab")
			(hide yes)
			(effects
				(font
					(size 1 1)
					(thickness 0.15)
				)
				(justify mirror)
			)
		)
		(property "Voltage" ""
			(at 233.975 -71.175 0)
			(layer "B.Fab")
			(hide yes)
			(effects
				(font
					(size 1 1)
					(thickness 0.15)
				)
				(justify mirror)
			)
		)
		(sheetname "LPDDR4")
		(sheetfile "lpddr4.kicad_sch")
		(attr smd)
		(fp_rect
			(start -0.72 0.38)
			(end 0.72 -0.38)
			(stroke
				(width 0.05)
				(type solid)
			)
			(fill no)
			(layer "B.CrtYd")
		)
		(fp_rect
			(start 0.3 -0.15)
			(end -0.301 0.149)
			(stroke
				(width 0.15)
				(type solid)
			)
			(fill no)
			(layer "B.Fab")
		)
		(pad "" smd roundrect
			(at -0.349 0.002 90)
			(size 0.318 0.36)
			(layers "B.Paste")
			(roundrect_rratio 0.25)
		)
		(pad "" smd roundrect
			(at 0.341 0.002 90)
			(size 0.318 0.36)
			(layers "B.Paste")
			(roundrect_rratio 0.25)
		)
		(pad "1" smd roundrect
			(at -0.321 0.002 90)
			(size 0.46 0.4)
			(layers "B.Cu" "B.Mask")
			(roundrect_rratio 0.25)
			(net 36 "GND")
			(pintype "passive")
		)
		(pad "2" smd roundrect
			(at 0.32 0.002 90)
			(size 0.46 0.4)
			(layers "B.Cu" "B.Mask")
			(roundrect_rratio 0.25)
			(net 189 "VDDQ")
			(pintype "passive")
		)
	)
)
